(kicad_pcb
	(version 20260206)
	(generator "pcbnew")
	(generator_version "10.0")
	(general
		(thickness 1.6)
		(legacy_teardrops no)
	)
	(paper "A4")
	(title_block
		(title "Wiwynn_Tioga_Pass_MB.brd")
		(comment 1 "Tioga Pass / footprints 1789-1796 of 4770")
	)
	(layers
		(0 "F.Cu" signal "TOP")
		(4 "In1.Cu" signal "L2GND")
		(6 "In2.Cu" signal "L3")
		(8 "In3.Cu" signal "L4GND")
		(10 "In4.Cu" signal "L5")
		(12 "In5.Cu" signal "L6GND")
		(14 "In6.Cu" signal "L7VCC")
		(16 "In7.Cu" signal "L8VCC")
		(18 "In8.Cu" signal "L9GND")
		(20 "In9.Cu" signal "L10")
		(22 "In10.Cu" signal "L11GND")
		(24 "In11.Cu" signal "L12")
		(26 "In12.Cu" signal "L13GND")
		(2 "B.Cu" signal "BOTTOM")
		(9 "F.Adhes" user "F.Adhesive")
		(11 "B.Adhes" user "B.Adhesive")
		(13 "F.Paste" user "Package Geometry/Pastemask Top")
		(15 "B.Paste" user "Package Geometry/Pastemask Bottom")
		(5 "F.SilkS" user "Ref Des/Silkscreen Top")
		(7 "B.SilkS" user "Ref Des/Silkscreen Bottom")
		(1 "F.Mask" user "Board Geometry/Soldermask Top")
		(3 "B.Mask" user "Board Geometry/Soldermask Bottom")
		(17 "Dwgs.User" user "User.Drawings")
		(19 "Cmts.User" user "User.Comments")
		(21 "Eco1.User" user "User.Eco1")
		(23 "Eco2.User" user "User.Eco2")
		(25 "Edge.Cuts" user "Board Geometry/Outline")
		(27 "Margin" user)
		(31 "F.CrtYd" user "Package Geometry/Place Bound Top")
		(29 "B.CrtYd" user "Package Geometry/Place Bound Bottom")
		(35 "F.Fab" user "Ref Des/Assembly Top")
		(33 "B.Fab" user "Ref Des/Assembly Bottom")
	)
	(footprint ""
		(layer "F.Cu")
		(at 163.277042 -34.671)
		(property "Reference" "C3F1"
			(at 0 0 0)
			(layer "F.SilkS")
			(hide yes)
			(effects
				(font
					(size 1.27 1.27)
				)
			)
		)
		(property "Value" ""
			(at 0 0 0)
			(layer "F.Fab")
			(effects
				(font
					(size 1.27 1.27)
				)
			)
		)
		(duplicate_pad_numbers_are_jumpers no)
		(fp_rect
			(start -0.500126 1.598422)
			(end 0.500126 -0.201422)
			(stroke
				(width 0)
				(type default)
			)
			(fill no)
			(layer "F.CrtYd")
		)
		(fp_line
			(start -0.500126 -0.201422)
			(end 0.500126 -0.201422)
			(stroke
				(width 0.1)
				(type default)
			)
			(layer "F.Fab")
		)
		(fp_line
			(start -0.500126 1.598422)
			(end -0.500126 -0.201422)
			(stroke
				(width 0.1)
				(type default)
			)
			(layer "F.Fab")
		)
		(fp_line
			(start 0.500126 -0.201422)
			(end 0.500126 1.598422)
			(stroke
				(width 0.1)
				(type default)
			)
			(layer "F.Fab")
		)
		(fp_line
			(start 0.500126 1.598422)
			(end -0.500126 1.598422)
			(stroke
				(width 0.1)
				(type default)
			)
			(layer "F.Fab")
		)
		(pad "1" smd rect
			(at 0 0 270)
			(size 0.889 0.9906)
			(layers "F.Cu" "F.Mask" "F.Paste")
			(net "P1V8_MCP_CPU1")
		)
		(pad "2" smd rect
			(at 0 1.397 270)
			(size 0.889 0.9906)
			(layers "F.Cu" "F.Mask" "F.Paste")
			(net "GND")
		)
		(zone
			(layer "F.Cu")
			(hatch none 0.5)
			(connect_pads
				(clearance 0)
			)
			(min_thickness 0.25)
			(keepout
				(tracks not_allowed)
				(vias allowed)
				(pads allowed)
				(copperpour not_allowed)
				(footprints allowed)
			)
			(placement
				(enabled no)
				(sheetname "")
			)
			(fill
				(thermal_gap 0.5)
				(thermal_bridge_width 0.5)
				(island_removal_mode 0)
			)
			(polygon
				(pts
					(xy 162.781742 -33.7185) (xy 163.772342 -33.7185) (xy 163.772342 -34.2265) (xy 162.781742 -34.2265)
				)
			)
		)
		(zone
			(layer "F.Cu")
			(hatch none 0.5)
			(connect_pads
				(clearance 0)
			)
			(min_thickness 0.25)
			(keepout
				(tracks allowed)
				(vias not_allowed)
				(pads allowed)
				(copperpour not_allowed)
				(footprints allowed)
			)
			(placement
				(enabled no)
				(sheetname "")
			)
			(fill
				(thermal_gap 0.5)
				(thermal_bridge_width 0.5)
				(island_removal_mode 0)
			)
			(polygon
				(pts
					(xy 162.781742 -33.7185) (xy 163.772342 -33.7185) (xy 163.772342 -34.2265) (xy 162.781742 -34.2265)
				)
			)
		)
	)
	(footprint ""
		(layer "F.Cu")
		(at 185.1406 -75.4253 180)
		(property "Reference" "C4D18"
			(at 0 0 180)
			(layer "F.SilkS")
			(hide yes)
			(effects
				(font
					(size 1.27 1.27)
				)
			)
		)
		(property "Value" ""
			(at 0 0 180)
			(layer "F.Fab")
			(effects
				(font
					(size 1.27 1.27)
				)
			)
		)
		(duplicate_pad_numbers_are_jumpers no)
		(fp_rect
			(start 0.3048 -0.1016)
			(end -0.3048 0.9906)
			(stroke
				(width 0)
				(type default)
			)
			(fill no)
			(layer "F.CrtYd")
		)
		(fp_line
			(start 0.3048 0.9906)
			(end 0.3048 -0.1016)
			(stroke
				(width 0.1)
				(type default)
			)
			(layer "F.Fab")
		)
		(fp_line
			(start 0.3048 -0.1016)
			(end -0.3048 -0.1016)
			(stroke
				(width 0.1)
				(type default)
			)
			(layer "F.Fab")
		)
		(fp_line
			(start -0.3048 0.9906)
			(end 0.3048 0.9906)
			(stroke
				(width 0.1)
				(type default)
			)
			(layer "F.Fab")
		)
		(fp_line
			(start -0.3048 -0.1016)
			(end -0.3048 0.9906)
			(stroke
				(width 0.1)
				(type default)
			)
			(layer "F.Fab")
		)
		(pad "1" smd rect
			(at 0 0 180)
			(size 0.508 0.508)
			(layers "F.Cu" "F.Mask" "F.Paste")
			(net "A_TSENSE_PVSA_CPU0")
		)
		(pad "2" smd rect
			(at 0 0.889 180)
			(size 0.508 0.508)
			(layers "F.Cu" "F.Mask" "F.Paste")
			(net "GND")
		)
		(zone
			(layer "F.Cu")
			(hatch none 0.5)
			(connect_pads
				(clearance 0)
			)
			(min_thickness 0.25)
			(keepout
				(tracks allowed)
				(vias not_allowed)
				(pads allowed)
				(copperpour not_allowed)
				(footprints allowed)
			)
			(placement
				(enabled no)
				(sheetname "")
			)
			(fill
				(thermal_gap 0.5)
				(thermal_bridge_width 0.5)
				(island_removal_mode 0)
			)
			(polygon
				(pts
					(xy 184.8866 -75.6793) (xy 185.3946 -75.6793) (xy 185.3946 -76.0603) (xy 184.8866 -76.0603)
				)
			)
		)
		(zone
			(layer "F.Cu")
			(hatch none 0.5)
			(connect_pads
				(clearance 0)
			)
			(min_thickness 0.25)
			(keepout
				(tracks not_allowed)
				(vias allowed)
				(pads allowed)
				(copperpour not_allowed)
				(footprints allowed)
			)
			(placement
				(enabled no)
				(sheetname "")
			)
			(fill
				(thermal_gap 0.5)
				(thermal_bridge_width 0.5)
				(island_removal_mode 0)
			)
			(polygon
				(pts
					(xy 184.8866 -75.6793) (xy 185.3946 -75.6793) (xy 185.3946 -76.0603) (xy 184.8866 -76.0603)
				)
			)
		)
	)
	(footprint ""
		(layer "F.Cu")
		(at 28.09748 -98.59772 90)
		(property "Reference" "RT37"
			(at 1.01473 0.656336 0)
			(unlocked yes)
			(layer "F.SilkS")
			(effects
				(font
					(size 0.4064 0.254)
					(thickness 0.1524)
				)
			)
		)
		(property "Value" ""
			(at 0 0 90)
			(layer "F.Fab")
			(effects
				(font
					(size 1.27 1.27)
				)
			)
		)
		(duplicate_pad_numbers_are_jumpers no)
		(fp_poly
			(pts
				(xy -0.4953 -0.2032) (xy 0.4953 -0.2032) (xy 0.4953 1.6002) (xy -0.4953 1.6002)
			)
			(stroke
				(width 0)
				(type default)
			)
			(fill no)
			(layer "F.CrtYd")
		)
		(fp_line
			(start 0.4953 -0.2032)
			(end 0.4953 1.6002)
			(stroke
				(width 0.1)
				(type default)
			)
			(layer "F.Fab")
		)
		(fp_line
			(start -0.4953 -0.2032)
			(end 0.4953 -0.2032)
			(stroke
				(width 0.1)
				(type default)
			)
			(layer "F.Fab")
		)
		(fp_line
			(start 0.4953 1.6002)
			(end -0.4953 1.6002)
			(stroke
				(width 0.1)
				(type default)
			)
			(layer "F.Fab")
		)
		(fp_line
			(start -0.4953 1.6002)
			(end -0.4953 -0.2032)
			(stroke
				(width 0.1)
				(type default)
			)
			(layer "F.Fab")
		)
		(pad "1" smd rect
			(at 0 0 90)
			(size 0.762 0.889)
			(layers "F.Cu" "F.Mask" "F.Paste")
			(net "VR_PVSA_CPU1_BOOT")
		)
		(pad "2" smd rect
			(at 0 1.397 90)
			(size 0.762 0.889)
			(layers "F.Cu" "F.Mask" "F.Paste")
			(net "VR_PVSA_CPU1_BOOT_R")
		)
		(zone
			(layer "F.Cu")
			(hatch none 0.5)
			(connect_pads
				(clearance 0)
			)
			(min_thickness 0.25)
			(keepout
				(tracks allowed)
				(vias not_allowed)
				(pads allowed)
				(copperpour not_allowed)
				(footprints allowed)
			)
			(placement
				(enabled no)
				(sheetname "")
			)
			(fill
				(thermal_gap 0.5)
				(thermal_bridge_width 0.5)
				(island_removal_mode 0)
			)
			(polygon
				(pts
					(xy 29.04998 -98.97872) (xy 28.54198 -98.97872) (xy 28.54198 -98.21672) (xy 29.04998 -98.21672)
				)
			)
		)
		(zone
			(layer "F.Cu")
			(hatch none 0.5)
			(connect_pads
				(clearance 0)
			)
			(min_thickness 0.25)
			(keepout
				(tracks not_allowed)
				(vias allowed)
				(pads allowed)
				(copperpour not_allowed)
				(footprints allowed)
			)
			(placement
				(enabled no)
				(sheetname "")
			)
			(fill
				(thermal_gap 0.5)
				(thermal_bridge_width 0.5)
				(island_removal_mode 0)
			)
			(polygon
				(pts
					(xy 29.04998 -98.21672) (xy 29.04998 -98.97872) (xy 28.54198 -98.97872) (xy 28.54198 -98.21672)
				)
			)
		)
	)
	(footprint ""
		(layer "F.Cu")
		(at 10.414 -131.826 90)
		(property "Reference" "L1B1"
			(at 0 0 90)
			(layer "F.SilkS")
			(hide yes)
			(effects
				(font
					(size 1.27 1.27)
				)
			)
		)
		(property "Value" "*"
			(at -3.5941 0.3429 90)
			(unlocked yes)
			(layer "F.Fab")
			(hide yes)
			(effects
				(font
					(size 1.27 1.016)
					(thickness 0.1524)
				)
			)
		)
		(property "Device Type" "IND-100NH-35-GP_DISCRET-G8-INDA"
			(at -3.5941 -1.1811 90)
			(unlocked yes)
			(layer "F.Fab")
			(hide yes)
			(effects
				(font
					(size 1.27 1.016)
					(thickness 0.1524)
				)
			)
		)
		(duplicate_pad_numbers_are_jumpers no)
		(fp_line
			(start 2.2479 -2.794)
			(end 2.2479 2.794)
			(stroke
				(width 0.1524)
				(type default)
			)
			(layer "F.SilkS")
		)
		(fp_line
			(start -2.2479 -2.794)
			(end 2.2479 -2.794)
			(stroke
				(width 0.1524)
				(type default)
			)
			(layer "F.SilkS")
		)
		(fp_line
			(start 2.2479 2.794)
			(end -2.2479 2.794)
			(stroke
				(width 0.1524)
				(type default)
			)
			(layer "F.SilkS")
		)
		(fp_line
			(start -2.2479 2.794)
			(end -2.2479 -2.794)
			(stroke
				(width 0.1524)
				(type default)
			)
			(layer "F.SilkS")
		)
		(fp_rect
			(start -1.9939 1.9939)
			(end 1.9939 -1.9939)
			(stroke
				(width 0)
				(type default)
			)
			(fill no)
			(layer "F.CrtYd")
		)
		(fp_poly
			(pts
				(xy -2.5019 2.8702) (xy -2.5019 1.9939) (xy 1.9939 1.9939) (xy 1.9939 -1.9939) (xy -1.9939 -1.9939)
				(xy -1.9939 1.9812) (xy -2.5019 1.9812) (xy -2.5019 -2.8702) (xy 2.5019 -2.8702) (xy 2.5019 2.8702)
			)
			(stroke
				(width 0)
				(type default)
			)
			(fill no)
			(layer "F.CrtYd")
		)
		(fp_rect
			(start -2.5019 2.8702)
			(end 2.5019 -2.8702)
			(stroke
				(width 0)
				(type default)
			)
			(fill no)
			(layer "F.Fab")
		)
		(pad "1" smd rect
			(at 0 -1.745996 90)
			(size 1.5494 1.6002)
			(layers "F.Cu" "F.Mask" "F.Paste")
			(net "P12V_STBY")
		)
		(pad "2" smd rect
			(at 0 1.745996 90)
			(size 1.5494 1.6002)
			(layers "F.Cu" "F.Mask" "F.Paste")
			(net "VR_FET_SW_P12V_STBY_PVDDQ_KLM")
		)
	)
	(footprint ""
		(layer "F.Cu")
		(at 32.672274 -101.472492 90)
		(property "Reference" "C1C17"
			(at 0 0 90)
			(layer "F.SilkS")
			(hide yes)
			(effects
				(font
					(size 1.27 1.27)
				)
			)
		)
		(property "Value" ""
			(at 0 0 90)
			(layer "F.Fab")
			(effects
				(font
					(size 1.27 1.27)
				)
			)
		)
		(duplicate_pad_numbers_are_jumpers no)
		(fp_rect
			(start 0.3048 0.9906)
			(end -0.3048 -0.1016)
			(stroke
				(width 0)
				(type default)
			)
			(fill no)
			(layer "F.CrtYd")
		)
		(fp_line
			(start 0.3048 -0.1016)
			(end -0.3048 -0.1016)
			(stroke
				(width 0.1)
				(type default)
			)
			(layer "F.Fab")
		)
		(fp_line
			(start -0.3048 -0.1016)
			(end -0.3048 0.9906)
			(stroke
				(width 0.1)
				(type default)
			)
			(layer "F.Fab")
		)
		(fp_line
			(start 0.3048 0.9906)
			(end 0.3048 -0.1016)
			(stroke
				(width 0.1)
				(type default)
			)
			(layer "F.Fab")
		)
		(fp_line
			(start -0.3048 0.9906)
			(end 0.3048 0.9906)
			(stroke
				(width 0.1)
				(type default)
			)
			(layer "F.Fab")
		)
		(pad "1" smd rect
			(at 0 0 90)
			(size 0.508 0.508)
			(layers "F.Cu" "F.Mask" "F.Paste")
			(net "VR_FET_SW_P12V_STBY_PVCCIN_CPU1")
		)
		(pad "2" smd rect
			(at 0 0.889 90)
			(size 0.508 0.508)
			(layers "F.Cu" "F.Mask" "F.Paste")
			(net "GND")
		)
		(zone
			(layer "F.Cu")
			(hatch none 0.5)
			(connect_pads
				(clearance 0)
			)
			(min_thickness 0.25)
			(keepout
				(tracks allowed)
				(vias not_allowed)
				(pads allowed)
				(copperpour not_allowed)
				(footprints allowed)
			)
			(placement
				(enabled no)
				(sheetname "")
			)
			(fill
				(thermal_gap 0.5)
				(thermal_bridge_width 0.5)
				(island_removal_mode 0)
			)
			(polygon
				(pts
					(xy 33.307274 -101.726492) (xy 32.926274 -101.726492) (xy 32.926274 -101.218492) (xy 33.307274 -101.218492)
				)
			)
		)
		(zone
			(layer "F.Cu")
			(hatch none 0.5)
			(connect_pads
				(clearance 0)
			)
			(min_thickness 0.25)
			(keepout
				(tracks not_allowed)
				(vias allowed)
				(pads allowed)
				(copperpour not_allowed)
				(footprints allowed)
			)
			(placement
				(enabled no)
				(sheetname "")
			)
			(fill
				(thermal_gap 0.5)
				(thermal_bridge_width 0.5)
				(island_removal_mode 0)
			)
			(polygon
				(pts
					(xy 33.307274 -101.726492) (xy 32.926274 -101.726492) (xy 32.926274 -101.218492) (xy 33.307274 -101.218492)
				)
			)
		)
	)
	(footprint ""
		(layer "F.Cu")
		(at 7.137146 -4.548886 90)
		(property "Reference" "R1G5"
			(at 0 0 90)
			(layer "F.SilkS")
			(hide yes)
			(effects
				(font
					(size 1.27 1.27)
				)
			)
		)
		(property "Value" ""
			(at 0 0 90)
			(layer "F.Fab")
			(effects
				(font
					(size 1.27 1.27)
				)
			)
		)
		(duplicate_pad_numbers_are_jumpers no)
		(fp_rect
			(start 0.2794 -0.1016)
			(end -0.2794 0.9906)
			(stroke
				(width 0)
				(type default)
			)
			(fill no)
			(layer "F.CrtYd")
		)
		(fp_line
			(start 0.2794 -0.1016)
			(end -0.2794 -0.1016)
			(stroke
				(width 0.1)
				(type default)
			)
			(layer "F.Fab")
		)
		(fp_line
			(start -0.2794 -0.1016)
			(end -0.2794 0.9906)
			(stroke
				(width 0.1)
				(type default)
			)
			(layer "F.Fab")
		)
		(fp_line
			(start 0.2794 0.9906)
			(end 0.2794 -0.1016)
			(stroke
				(width 0.1)
				(type default)
			)
			(layer "F.Fab")
		)
		(fp_line
			(start -0.2794 0.9906)
			(end 0.2794 0.9906)
			(stroke
				(width 0.1)
				(type default)
			)
			(layer "F.Fab")
		)
		(pad "1" smd rect
			(at 0 0 90)
			(size 0.508 0.508)
			(layers "F.Cu" "F.Mask" "F.Paste")
			(net "VSENSE_PVDDQ_GHJ_P")
		)
		(pad "2" smd rect
			(at 0 0.889 90)
			(size 0.508 0.508)
			(layers "F.Cu" "F.Mask" "F.Paste")
			(net "VR_PVDDQ_GHJ_AVSP")
		)
		(zone
			(layer "F.Cu")
			(hatch none 0.5)
			(connect_pads
				(clearance 0)
			)
			(min_thickness 0.25)
			(keepout
				(tracks allowed)
				(vias not_allowed)
				(pads allowed)
				(copperpour not_allowed)
				(footprints allowed)
			)
			(placement
				(enabled no)
				(sheetname "")
			)
			(fill
				(thermal_gap 0.5)
				(thermal_bridge_width 0.5)
				(island_removal_mode 0)
			)
			(polygon
				(pts
					(xy 7.391146 -4.802886) (xy 7.391146 -4.294886) (xy 7.772146 -4.294886) (xy 7.772146 -4.802886)
				)
			)
		)
		(zone
			(layer "F.Cu")
			(hatch none 0.5)
			(connect_pads
				(clearance 0)
			)
			(min_thickness 0.25)
			(keepout
				(tracks not_allowed)
				(vias allowed)
				(pads allowed)
				(copperpour not_allowed)
				(footprints allowed)
			)
			(placement
				(enabled no)
				(sheetname "")
			)
			(fill
				(thermal_gap 0.5)
				(thermal_bridge_width 0.5)
				(island_removal_mode 0)
			)
			(polygon
				(pts
					(xy 7.391146 -4.802886) (xy 7.391146 -4.294886) (xy 7.772146 -4.294886) (xy 7.772146 -4.802886)
				)
			)
		)
	)
	(footprint ""
		(layer "F.Cu")
		(at 401.8915 -49.403 90)
		(property "Reference" "C7F1"
			(at 0 0 90)
			(layer "F.SilkS")
			(hide yes)
			(effects
				(font
					(size 1.27 1.27)
				)
			)
		)
		(property "Value" ""
			(at 0 0 90)
			(layer "F.Fab")
			(effects
				(font
					(size 1.27 1.27)
				)
			)
		)
		(duplicate_pad_numbers_are_jumpers no)
		(fp_poly
			(pts
				(xy 0.3048 -0.1016) (xy 0.3048 0.9906) (xy -0.3048 0.9906) (xy -0.3048 -0.1016)
			)
			(stroke
				(width 0)
				(type default)
			)
			(fill no)
			(layer "F.CrtYd")
		)
		(fp_line
			(start 0.3048 -0.1016)
			(end -0.3048 -0.1016)
			(stroke
				(width 0.1)
				(type default)
			)
			(layer "F.Fab")
		)
		(fp_line
			(start -0.3048 -0.1016)
			(end -0.3048 0.9906)
			(stroke
				(width 0.1)
				(type default)
			)
			(layer "F.Fab")
		)
		(fp_line
			(start 0.3048 0.9906)
			(end 0.3048 -0.1016)
			(stroke
				(width 0.1)
				(type default)
			)
			(layer "F.Fab")
		)
		(fp_line
			(start -0.3048 0.9906)
			(end 0.3048 0.9906)
			(stroke
				(width 0.1)
				(type default)
			)
			(layer "F.Fab")
		)
		(pad "1" smd rect
			(at 0 0 90)
			(size 0.508 0.508)
			(layers "F.Cu" "F.Mask" "F.Paste")
			(net "P3V3_STBY")
		)
		(pad "2" smd rect
			(at 0 0.889 90)
			(size 0.508 0.508)
			(layers "F.Cu" "F.Mask" "F.Paste")
			(net "GND")
		)
		(zone
			(layer "F.Cu")
			(hatch none 0.5)
			(connect_pads
				(clearance 0)
			)
			(min_thickness 0.25)
			(keepout
				(tracks allowed)
				(vias not_allowed)
				(pads allowed)
				(copperpour not_allowed)
				(footprints allowed)
			)
			(placement
				(enabled no)
				(sheetname "")
			)
			(fill
				(thermal_gap 0.5)
				(thermal_bridge_width 0.5)
				(island_removal_mode 0)
			)
			(polygon
				(pts
					(xy 402.1455 -49.149) (xy 402.1455 -49.657) (xy 402.5265 -49.657) (xy 402.5265 -49.149)
				)
			)
		)
		(zone
			(layer "F.Cu")
			(hatch none 0.5)
			(connect_pads
				(clearance 0)
			)
			(min_thickness 0.25)
			(keepout
				(tracks not_allowed)
				(vias allowed)
				(pads allowed)
				(copperpour not_allowed)
				(footprints allowed)
			)
			(placement
				(enabled no)
				(sheetname "")
			)
			(fill
				(thermal_gap 0.5)
				(thermal_bridge_width 0.5)
				(island_removal_mode 0)
			)
			(polygon
				(pts
					(xy 402.5265 -49.149) (xy 402.5265 -49.657) (xy 402.1455 -49.657) (xy 402.1455 -49.149)
				)
			)
		)
	)
	(footprint ""
		(layer "F.Cu")
		(at 375.539 -132.08 180)
		(property "Reference" "C7B20"
			(at 0 0 180)
			(layer "F.SilkS")
			(hide yes)
			(effects
				(font
					(size 1.27 1.27)
				)
			)
		)
		(property "Value" ""
			(at 0 0 180)
			(layer "F.Fab")
			(effects
				(font
					(size 1.27 1.27)
				)
			)
		)
		(duplicate_pad_numbers_are_jumpers no)
		(fp_poly
			(pts
				(xy -0.4953 -0.2032) (xy 0.4953 -0.2032) (xy 0.4953 1.6002) (xy -0.4953 1.6002)
			)
			(stroke
				(width 0)
				(type default)
			)
			(fill no)
			(layer "F.CrtYd")
		)
		(fp_line
			(start 0.4953 1.6002)
			(end -0.4953 1.6002)
			(stroke
				(width 0.1)
				(type default)
			)
			(layer "F.Fab")
		)
		(fp_line
			(start 0.4953 -0.2032)
			(end 0.4953 1.6002)
			(stroke
				(width 0.1)
				(type default)
			)
			(layer "F.Fab")
		)
		(fp_line
			(start -0.4953 1.6002)
			(end -0.4953 -0.2032)
			(stroke
				(width 0.1)
				(type default)
			)
			(layer "F.Fab")
		)
		(fp_line
			(start -0.4953 -0.2032)
			(end 0.4953 -0.2032)
			(stroke
				(width 0.1)
				(type default)
			)
			(layer "F.Fab")
		)
		(pad "1" smd rect
			(at 0 0 180)
			(size 0.762 0.889)
			(layers "F.Cu" "F.Mask" "F.Paste")
			(net "P1V05_PCH_STBY")
		)
		(pad "2" smd rect
			(at 0 1.397 180)
			(size 0.762 0.889)
			(layers "F.Cu" "F.Mask" "F.Paste")
			(net "GND")
		)
		(zone
			(layer "F.Cu")
			(hatch none 0.5)
			(connect_pads
				(clearance 0)
			)
			(min_thickness 0.25)
			(keepout
				(tracks not_allowed)
				(vias allowed)
				(pads allowed)
				(copperpour not_allowed)
				(footprints allowed)
			)
			(placement
				(enabled no)
				(sheetname "")
			)
			(fill
				(thermal_gap 0.5)
				(thermal_bridge_width 0.5)
				(island_removal_mode 0)
			)
			(polygon
				(pts
					(xy 375.92 -132.5245) (xy 375.158 -132.5245) (xy 375.158 -133.0325) (xy 375.92 -133.0325)
				)
			)
		)
	)
)
